(kicad_pcb
	(version 20260206)
	(generator "pcbnew")
	(generator_version "10.0")
	(general
		(thickness 1.6)
		(legacy_teardrops no)
	)
	(paper "A4")
	(title_block
		(title "Bryce Canyon_Front Panel_16369-1_OCP.brd")
		(comment 1 "Bryce Canyon / footprints 103-108 of 154")
	)
	(layers
		(0 "F.Cu" signal "TOP")
		(4 "In1.Cu" signal "L2GND")
		(6 "In2.Cu" signal "L3VCC")
		(2 "B.Cu" signal "BOTTOM")
		(9 "F.Adhes" user "F.Adhesive")
		(11 "B.Adhes" user "B.Adhesive")
		(13 "F.Paste" user "Package Geometry/Pastemask Top")
		(15 "B.Paste" user "Package Geometry/Pastemask Bottom")
		(5 "F.SilkS" user "Ref Des/Silkscreen Top")
		(7 "B.SilkS" user "Ref Des/Silkscreen Bottom")
		(1 "F.Mask" user "Board Geometry/Soldermask Top")
		(3 "B.Mask" user "Board Geometry/Soldermask Bottom")
		(17 "Dwgs.User" user "User.Drawings")
		(19 "Cmts.User" user "User.Comments")
		(21 "Eco1.User" user "User.Eco1")
		(23 "Eco2.User" user "User.Eco2")
		(25 "Edge.Cuts" user "Board Geometry/Outline")
		(27 "Margin" user)
		(31 "F.CrtYd" user "Package Geometry/Place Bound Top")
		(29 "B.CrtYd" user "Package Geometry/Place Bound Bottom")
		(35 "F.Fab" user "Ref Des/Assembly Top")
		(33 "B.Fab" user "Ref Des/Assembly Bottom")
	)
	(footprint ""
		(layer "F.Cu")
		(at 10.094468 -27.776932 -90)
		(property "Reference" "R48"
			(at 0 0 270)
			(layer "F.SilkS")
			(hide yes)
			(effects
				(font
					(size 1.27 1.27)
				)
			)
		)
		(property "Value" "4K7R2F-GP"
			(at 0.064008 -4.679696 270)
			(unlocked yes)
			(layer "F.Fab")
			(hide yes)
			(effects
				(font
					(size 2.54 2.54)
					(thickness 0.381)
				)
			)
		)
		(property "Device Type" "R402H16"
			(at 0.064008 -6.203696 270)
			(unlocked yes)
			(layer "F.Fab")
			(hide yes)
			(effects
				(font
					(size 2.54 2.54)
					(thickness 0.381)
				)
			)
		)
		(duplicate_pad_numbers_are_jumpers no)
		(fp_line
			(start -0.508 -0.9398)
			(end -0.508 0.9398)
			(stroke
				(width 0.1524)
				(type default)
			)
			(layer "F.SilkS")
		)
		(fp_line
			(start 0.508 -0.9398)
			(end -0.508 -0.9398)
			(stroke
				(width 0.1524)
				(type default)
			)
			(layer "F.SilkS")
		)
		(fp_rect
			(start -0.508 0.9398)
			(end 0.508 -0.9398)
			(stroke
				(width 0)
				(type default)
			)
			(fill no)
			(layer "F.CrtYd")
		)
		(fp_rect
			(start -0.508 0.9398)
			(end 0.508 -0.9398)
			(stroke
				(width 0)
				(type default)
			)
			(fill no)
			(layer "F.Fab")
		)
		(pad "1" smd custom
			(at 0 -0.4445 270)
			(size 0.1397 0.1397)
			(layers "F.Cu" "F.Mask" "F.Paste")
			(net "P3V3_STBY_A")
			(options
				(clearance outline)
				(anchor circle)
			)
			(primitives
				(gr_poly
					(pts
						(arc
							(start -0.1778 -0.2794)
							(mid -0.249642 -0.249642)
							(end -0.2794 -0.1778)
						)
						(arc
							(start -0.2794 0.1778)
							(mid -0.249642 0.249642)
							(end -0.1778 0.2794)
						)
						(arc
							(start 0.1778 0.2794)
							(mid 0.249642 0.249642)
							(end 0.2794 0.1778)
						)
						(arc
							(start 0.2794 -0.1778)
							(mid 0.249642 -0.249642)
							(end 0.1778 -0.2794)
						)
					)
					(width 0)
					(fill yes)
				)
			)
		)
		(pad "2" smd custom
			(at 0 0.4445 270)
			(size 0.1397 0.1397)
			(layers "F.Cu" "F.Mask" "F.Paste")
			(net "RST_A_TS")
			(options
				(clearance outline)
				(anchor circle)
			)
			(primitives
				(gr_poly
					(pts
						(arc
							(start -0.1778 -0.2794)
							(mid -0.249642 -0.249642)
							(end -0.2794 -0.1778)
						)
						(arc
							(start -0.2794 0.1778)
							(mid -0.249642 0.249642)
							(end -0.1778 0.2794)
						)
						(arc
							(start 0.1778 0.2794)
							(mid 0.249642 0.249642)
							(end 0.2794 0.1778)
						)
						(arc
							(start 0.2794 -0.1778)
							(mid 0.249642 -0.249642)
							(end 0.1778 -0.2794)
						)
					)
					(width 0)
					(fill yes)
				)
			)
		)
	)
	(footprint ""
		(layer "F.Cu")
		(at 3.0734 -19.177 180)
		(property "Reference" "R4"
			(at 0 0 180)
			(layer "F.SilkS")
			(hide yes)
			(effects
				(font
					(size 1.27 1.27)
				)
			)
		)
		(property "Value" "4K7R2F-GP"
			(at 0.064008 -4.679696 180)
			(unlocked yes)
			(layer "F.Fab")
			(hide yes)
			(effects
				(font
					(size 2.54 2.54)
					(thickness 0.381)
				)
			)
		)
		(property "Device Type" "R402H16"
			(at 0.064008 -6.203696 180)
			(unlocked yes)
			(layer "F.Fab")
			(hide yes)
			(effects
				(font
					(size 2.54 2.54)
					(thickness 0.381)
				)
			)
		)
		(duplicate_pad_numbers_are_jumpers no)
		(fp_line
			(start 0.508 -0.9398)
			(end -0.508 -0.9398)
			(stroke
				(width 0.1524)
				(type default)
			)
			(layer "F.SilkS")
		)
		(fp_line
			(start -0.508 -0.9398)
			(end -0.508 0.9398)
			(stroke
				(width 0.1524)
				(type default)
			)
			(layer "F.SilkS")
		)
		(fp_rect
			(start -0.508 0.9398)
			(end 0.508 -0.9398)
			(stroke
				(width 0)
				(type default)
			)
			(fill no)
			(layer "F.CrtYd")
		)
		(fp_rect
			(start -0.508 0.9398)
			(end 0.508 -0.9398)
			(stroke
				(width 0)
				(type default)
			)
			(fill no)
			(layer "F.Fab")
		)
		(pad "1" smd custom
			(at 0 -0.4445 180)
			(size 0.1397 0.1397)
			(layers "F.Cu" "F.Mask" "F.Paste")
			(net "P3V3_STBY_A")
			(options
				(clearance outline)
				(anchor circle)
			)
			(primitives
				(gr_poly
					(pts
						(arc
							(start -0.1778 -0.2794)
							(mid -0.249642 -0.249642)
							(end -0.2794 -0.1778)
						)
						(arc
							(start -0.2794 0.1778)
							(mid -0.249642 0.249642)
							(end -0.1778 0.2794)
						)
						(arc
							(start 0.1778 0.2794)
							(mid 0.249642 0.249642)
							(end 0.2794 0.1778)
						)
						(arc
							(start 0.2794 -0.1778)
							(mid 0.249642 -0.249642)
							(end 0.1778 -0.2794)
						)
					)
					(width 0)
					(fill yes)
				)
			)
		)
		(pad "2" smd custom
			(at 0 0.4445 180)
			(size 0.1397 0.1397)
			(layers "F.Cu" "F.Mask" "F.Paste")
			(net "I2C_DEBUG_A_SDA")
			(options
				(clearance outline)
				(anchor circle)
			)
			(primitives
				(gr_poly
					(pts
						(arc
							(start -0.1778 -0.2794)
							(mid -0.249642 -0.249642)
							(end -0.2794 -0.1778)
						)
						(arc
							(start -0.2794 0.1778)
							(mid -0.249642 0.249642)
							(end -0.1778 0.2794)
						)
						(arc
							(start 0.1778 0.2794)
							(mid 0.249642 0.249642)
							(end 0.2794 0.1778)
						)
						(arc
							(start 0.2794 -0.1778)
							(mid 0.249642 -0.249642)
							(end 0.1778 -0.2794)
						)
					)
					(width 0)
					(fill yes)
				)
			)
		)
	)
	(footprint ""
		(layer "F.Cu")
		(at 48.90008 -34.99993)
		(property "Reference" "SW4"
			(at 0 0 0)
			(layer "F.SilkS")
			(hide yes)
			(effects
				(font
					(size 1.27 1.27)
				)
			)
		)
		(property "Value" "SW-TACT-4P-214-GP"
			(at 5.97154 0.7747 0)
			(unlocked yes)
			(layer "F.Fab")
			(hide yes)
			(effects
				(font
					(size 2.54 2.54)
					(thickness 0.381)
				)
			)
		)
		(property "Device Type" "DTSM-62N-Q-TR"
			(at 5.97154 -0.7493 0)
			(unlocked yes)
			(layer "F.Fab")
			(hide yes)
			(effects
				(font
					(size 2.54 2.54)
					(thickness 0.381)
				)
			)
		)
		(duplicate_pad_numbers_are_jumpers no)
		(fp_line
			(start -5.0927 -2.8956)
			(end -5.0927 -1.6002)
			(stroke
				(width 0.3302)
				(type default)
			)
			(layer "F.SilkS")
		)
		(fp_line
			(start -5.0038 -3.3528)
			(end 5.0038 -3.3528)
			(stroke
				(width 0.1524)
				(type default)
			)
			(layer "F.SilkS")
		)
		(fp_line
			(start -5.0038 -1.3462)
			(end -5.0038 -3.3528)
			(stroke
				(width 0.1524)
				(type default)
			)
			(layer "F.SilkS")
		)
		(fp_line
			(start -5.0038 1.3462)
			(end -3.3528 1.3462)
			(stroke
				(width 0.1524)
				(type default)
			)
			(layer "F.SilkS")
		)
		(fp_line
			(start -5.0038 3.3528)
			(end -5.0038 1.3462)
			(stroke
				(width 0.1524)
				(type default)
			)
			(layer "F.SilkS")
		)
		(fp_line
			(start -3.3528 -1.3462)
			(end -5.0038 -1.3462)
			(stroke
				(width 0.1524)
				(type default)
			)
			(layer "F.SilkS")
		)
		(fp_line
			(start -3.3528 1.3462)
			(end -3.3528 -1.3462)
			(stroke
				(width 0.1524)
				(type default)
			)
			(layer "F.SilkS")
		)
		(fp_line
			(start 3.3528 -1.3462)
			(end 3.3528 1.3462)
			(stroke
				(width 0.1524)
				(type default)
			)
			(layer "F.SilkS")
		)
		(fp_line
			(start 3.3528 1.3462)
			(end 5.0038 1.3462)
			(stroke
				(width 0.1524)
				(type default)
			)
			(layer "F.SilkS")
		)
		(fp_line
			(start 5.0038 -3.3528)
			(end 5.0038 -1.3462)
			(stroke
				(width 0.1524)
				(type default)
			)
			(layer "F.SilkS")
		)
		(fp_line
			(start 5.0038 -1.3462)
			(end 3.3528 -1.3462)
			(stroke
				(width 0.1524)
				(type default)
			)
			(layer "F.SilkS")
		)
		(fp_line
			(start 5.0038 1.3462)
			(end 5.0038 3.3528)
			(stroke
				(width 0.1524)
				(type default)
			)
			(layer "F.SilkS")
		)
		(fp_line
			(start 5.0038 3.3528)
			(end -5.0038 3.3528)
			(stroke
				(width 0.1524)
				(type default)
			)
			(layer "F.SilkS")
		)
		(fp_poly
			(pts
				(xy -5.072888 -2.29108) (xy -5.707888 -1.65608) (xy -5.707888 -2.92608)
			)
			(stroke
				(width 0)
				(type default)
			)
			(fill yes)
			(layer "F.SilkS")
		)
		(fp_poly
			(pts
				(xy -3.0988 3.0988) (xy -3.0988 2.5908) (xy -4.4958 2.5908) (xy -4.4958 1.8796) (xy -3.0988 1.8796)
				(xy -3.0988 -1.8796) (xy -4.4958 -1.8796) (xy -4.4958 -2.5908) (xy -3.0988 -2.5908) (xy -3.0988 -3.0988)
				(xy 3.0988 -3.0988) (xy 3.0988 -2.5908) (xy 4.4958 -2.5908) (xy 4.4958 -1.8796) (xy 3.0988 -1.8796)
				(xy 3.0988 1.8796) (xy 4.4958 1.8796) (xy 4.4958 2.5908) (xy 3.0988 2.5908) (xy 3.0988 3.0988)
			)
			(stroke
				(width 0)
				(type default)
			)
			(fill no)
			(layer "F.CrtYd")
		)
		(fp_poly
			(pts
				(xy -5.2578 3.6068) (xy -5.2578 1.0922) (xy -3.6068 1.0922) (xy -3.6068 -1.0922) (xy -5.2578 -1.0922)
				(xy -5.2578 -3.6068) (xy 5.2578 -3.6068) (xy 5.2578 -1.0922) (xy 3.6068 -1.0922) (xy 3.6068 -0.00635)
				(xy 3.0988 -0.00635) (xy 3.0988 -1.8796) (xy 4.4958 -1.8796) (xy 4.4958 -2.5908) (xy 3.0988 -2.5908)
				(xy 3.0988 -3.0988) (xy -3.0988 -3.0988) (xy -3.0988 -2.5908) (xy -4.4958 -2.5908) (xy -4.4958 -1.8796)
				(xy -3.0988 -1.8796) (xy -3.0988 1.8796) (xy -4.4958 1.8796) (xy -4.4958 2.5908) (xy -3.0988 2.5908)
				(xy -3.0988 3.0988) (xy 3.0988 3.0988) (xy 3.0988 2.5908) (xy 4.4958 2.5908) (xy 4.4958 1.8796)
				(xy 3.0988 1.8796) (xy 3.0988 0.00635) (xy 3.6068 0.00635) (xy 3.6068 1.0922) (xy 5.2578 1.0922)
				(xy 5.2578 3.6068)
			)
			(stroke
				(width 0)
				(type default)
			)
			(fill no)
			(layer "F.CrtYd")
		)
		(fp_poly
			(pts
				(xy -5.2578 3.6068) (xy -5.2578 1.0922) (xy -3.6068 1.0922) (xy -3.6068 -1.0922) (xy -5.2578 -1.0922)
				(xy -5.2578 -3.6068) (xy 5.2578 -3.6068) (xy 5.2578 -1.0922) (xy 3.6068 -1.0922) (xy 3.6068 1.0922)
				(xy 5.2578 1.0922) (xy 5.2578 3.6068)
			)
			(stroke
				(width 0)
				(type default)
			)
			(fill no)
			(layer "F.Fab")
		)
		(pad "T1" smd rect
			(at -3.9751 -2.249932)
			(size 1.5494 1.2954)
			(layers "F.Cu" "F.Mask" "F.Paste")
			(net "SYS_RESET_BTN_B")
		)
		(pad "T2" smd rect
			(at 3.9751 -2.249932)
			(size 1.5494 1.2954)
			(layers "F.Cu" "F.Mask" "F.Paste")
			(net "SYS_RESET_BTN_B")
		)
		(pad "T3" smd rect
			(at -3.9751 2.249932)
			(size 1.5494 1.2954)
			(layers "F.Cu" "F.Mask" "F.Paste")
			(net "GND")
		)
		(pad "T4" smd rect
			(at 3.9751 2.249932)
			(size 1.5494 1.2954)
			(layers "F.Cu" "F.Mask" "F.Paste")
			(net "GND")
		)
	)
	(footprint ""
		(layer "F.Cu")
		(at 24.910034 -12.68095 180)
		(property "Reference" "R79"
			(at 0 0 180)
			(layer "F.SilkS")
			(hide yes)
			(effects
				(font
					(size 1.27 1.27)
				)
			)
		)
		(property "Value" "4K7R2F-GP"
			(at 0.064008 -3.993896 180)
			(unlocked yes)
			(layer "F.Fab")
			(hide yes)
			(effects
				(font
					(size 1.016 1.016)
					(thickness 0.1524)
				)
			)
		)
		(property "Device Type" "R402H16"
			(at 0.064008 -5.517896 180)
			(unlocked yes)
			(layer "F.Fab")
			(hide yes)
			(effects
				(font
					(size 1.016 1.016)
					(thickness 0.1524)
				)
			)
		)
		(duplicate_pad_numbers_are_jumpers no)
		(fp_line
			(start 0.508 -0.9398)
			(end -0.508 -0.9398)
			(stroke
				(width 0.1524)
				(type default)
			)
			(layer "F.SilkS")
		)
		(fp_line
			(start -0.508 -0.9398)
			(end -0.508 0.9398)
			(stroke
				(width 0.1524)
				(type default)
			)
			(layer "F.SilkS")
		)
		(fp_rect
			(start -0.508 0.9398)
			(end 0.508 -0.9398)
			(stroke
				(width 0)
				(type default)
			)
			(fill no)
			(layer "F.CrtYd")
		)
		(fp_rect
			(start -0.508 0.9398)
			(end 0.508 -0.9398)
			(stroke
				(width 0)
				(type default)
			)
			(fill no)
			(layer "F.Fab")
		)
		(pad "1" smd custom
			(at 0 -0.4445 180)
			(size 0.1397 0.1397)
			(layers "F.Cu" "F.Mask" "F.Paste")
			(net "P3V3_STBY_A")
			(options
				(clearance outline)
				(anchor circle)
			)
			(primitives
				(gr_poly
					(pts
						(arc
							(start -0.1778 -0.2794)
							(mid -0.249642 -0.249642)
							(end -0.2794 -0.1778)
						)
						(arc
							(start -0.2794 0.1778)
							(mid -0.249642 0.249642)
							(end -0.1778 0.2794)
						)
						(arc
							(start 0.1778 0.2794)
							(mid 0.249642 0.249642)
							(end 0.2794 0.1778)
						)
						(arc
							(start 0.2794 -0.1778)
							(mid 0.249642 -0.249642)
							(end 0.1778 -0.2794)
						)
					)
					(width 0)
					(fill yes)
				)
			)
		)
		(pad "2" smd custom
			(at 0 0.4445 180)
			(size 0.1397 0.1397)
			(layers "F.Cu" "F.Mask" "F.Paste")
			(net "D_FLIP_CLR_A#")
			(options
				(clearance outline)
				(anchor circle)
			)
			(primitives
				(gr_poly
					(pts
						(arc
							(start -0.1778 -0.2794)
							(mid -0.249642 -0.249642)
							(end -0.2794 -0.1778)
						)
						(arc
							(start -0.2794 0.1778)
							(mid -0.249642 0.249642)
							(end -0.1778 0.2794)
						)
						(arc
							(start 0.1778 0.2794)
							(mid 0.249642 0.249642)
							(end 0.2794 0.1778)
						)
						(arc
							(start 0.2794 -0.1778)
							(mid 0.249642 -0.249642)
							(end 0.1778 -0.2794)
						)
					)
					(width 0)
					(fill yes)
				)
			)
		)
	)
	(footprint ""
		(layer "F.Cu")
		(at 56.515 -10.287)
		(property "Reference" "R71"
			(at 0 0 0)
			(layer "F.SilkS")
			(hide yes)
			(effects
				(font
					(size 1.27 1.27)
				)
			)
		)
		(property "Value" "4K7R2F-GP"
			(at 0.064008 -3.993896 0)
			(unlocked yes)
			(layer "F.Fab")
			(hide yes)
			(effects
				(font
					(size 1.016 1.016)
					(thickness 0.1524)
				)
			)
		)
		(property "Device Type" "R402H16"
			(at 0.064008 -5.517896 0)
			(unlocked yes)
			(layer "F.Fab")
			(hide yes)
			(effects
				(font
					(size 1.016 1.016)
					(thickness 0.1524)
				)
			)
		)
		(duplicate_pad_numbers_are_jumpers no)
		(fp_line
			(start -0.508 -0.9398)
			(end -0.508 0.9398)
			(stroke
				(width 0.1524)
				(type default)
			)
			(layer "F.SilkS")
		)
		(fp_line
			(start 0.508 -0.9398)
			(end -0.508 -0.9398)
			(stroke
				(width 0.1524)
				(type default)
			)
			(layer "F.SilkS")
		)
		(fp_rect
			(start -0.508 0.9398)
			(end 0.508 -0.9398)
			(stroke
				(width 0)
				(type default)
			)
			(fill no)
			(layer "F.CrtYd")
		)
		(fp_rect
			(start -0.508 0.9398)
			(end 0.508 -0.9398)
			(stroke
				(width 0)
				(type default)
			)
			(fill no)
			(layer "F.Fab")
		)
		(pad "1" smd custom
			(at 0 -0.4445)
			(size 0.1397 0.1397)
			(layers "F.Cu" "F.Mask" "F.Paste")
			(net "TCA9555_B_A1")
			(options
				(clearance outline)
				(anchor circle)
			)
			(primitives
				(gr_poly
					(pts
						(arc
							(start -0.1778 -0.2794)
							(mid -0.249642 -0.249642)
							(end -0.2794 -0.1778)
						)
						(arc
							(start -0.2794 0.1778)
							(mid -0.249642 0.249642)
							(end -0.1778 0.2794)
						)
						(arc
							(start 0.1778 0.2794)
							(mid 0.249642 0.249642)
							(end 0.2794 0.1778)
						)
						(arc
							(start 0.2794 -0.1778)
							(mid 0.249642 -0.249642)
							(end 0.1778 -0.2794)
						)
					)
					(width 0)
					(fill yes)
				)
			)
		)
		(pad "2" smd custom
			(at 0 0.4445)
			(size 0.1397 0.1397)
			(layers "F.Cu" "F.Mask" "F.Paste")
			(net "GND")
			(options
				(clearance outline)
				(anchor circle)
			)
			(primitives
				(gr_poly
					(pts
						(arc
							(start -0.1778 -0.2794)
							(mid -0.249642 -0.249642)
							(end -0.2794 -0.1778)
						)
						(arc
							(start -0.2794 0.1778)
							(mid -0.249642 0.249642)
							(end -0.1778 0.2794)
						)
						(arc
							(start 0.1778 0.2794)
							(mid 0.249642 0.249642)
							(end 0.2794 0.1778)
						)
						(arc
							(start 0.2794 -0.1778)
							(mid 0.249642 -0.249642)
							(end 0.1778 -0.2794)
						)
					)
					(width 0)
					(fill yes)
				)
			)
		)
	)
	(footprint ""
		(layer "F.Cu")
		(at 47.8155 -15.442184)
		(property "Reference" "R69"
			(at 0 0 0)
			(layer "F.SilkS")
			(hide yes)
			(effects
				(font
					(size 1.27 1.27)
				)
			)
		)
		(property "Value" "4K7R2F-GP"
			(at 0.064008 -3.993896 0)
			(unlocked yes)
			(layer "F.Fab")
			(hide yes)
			(effects
				(font
					(size 1.016 1.016)
					(thickness 0.1524)
				)
			)
		)
		(property "Device Type" "R402H16"
			(at 0.064008 -5.517896 0)
			(unlocked yes)
			(layer "F.Fab")
			(hide yes)
			(effects
				(font
					(size 1.016 1.016)
					(thickness 0.1524)
				)
			)
		)
		(duplicate_pad_numbers_are_jumpers no)
		(fp_line
			(start -0.508 -0.9398)
			(end -0.508 0.9398)
			(stroke
				(width 0.1524)
				(type default)
			)
			(layer "F.SilkS")
		)
		(fp_line
			(start 0.508 -0.9398)
			(end -0.508 -0.9398)
			(stroke
				(width 0.1524)
				(type default)
			)
			(layer "F.SilkS")
		)
		(fp_rect
			(start -0.508 0.9398)
			(end 0.508 -0.9398)
			(stroke
				(width 0)
				(type default)
			)
			(fill no)
			(layer "F.CrtYd")
		)
		(fp_rect
			(start -0.508 0.9398)
			(end 0.508 -0.9398)
			(stroke
				(width 0)
				(type default)
			)
			(fill no)
			(layer "F.Fab")
		)
		(pad "1" smd custom
			(at 0 -0.4445)
			(size 0.1397 0.1397)
			(layers "F.Cu" "F.Mask" "F.Paste")
			(net "P3V3_STBY_B")
			(options
				(clearance outline)
				(anchor circle)
			)
			(primitives
				(gr_poly
					(pts
						(arc
							(start -0.1778 -0.2794)
							(mid -0.249642 -0.249642)
							(end -0.2794 -0.1778)
						)
						(arc
							(start -0.2794 0.1778)
							(mid -0.249642 0.249642)
							(end -0.1778 0.2794)
						)
						(arc
							(start 0.1778 0.2794)
							(mid 0.249642 0.249642)
							(end 0.2794 0.1778)
						)
						(arc
							(start 0.2794 -0.1778)
							(mid 0.249642 -0.249642)
							(end 0.1778 -0.2794)
						)
					)
					(width 0)
					(fill yes)
				)
			)
		)
		(pad "2" smd custom
			(at 0 0.4445)
			(size 0.1397 0.1397)
			(layers "F.Cu" "F.Mask" "F.Paste")
			(net "TCA9555_B_A0")
			(options
				(clearance outline)
				(anchor circle)
			)
			(primitives
				(gr_poly
					(pts
						(arc
							(start -0.1778 -0.2794)
							(mid -0.249642 -0.249642)
							(end -0.2794 -0.1778)
						)
						(arc
							(start -0.2794 0.1778)
							(mid -0.249642 0.249642)
							(end -0.1778 0.2794)
						)
						(arc
							(start 0.1778 0.2794)
							(mid 0.249642 0.249642)
							(end 0.2794 0.1778)
						)
						(arc
							(start 0.2794 -0.1778)
							(mid 0.249642 -0.249642)
							(end 0.1778 -0.2794)
						)
					)
					(width 0)
					(fill yes)
				)
			)
		)
	)
)
